(kicad_pcb
	(version 20241229)
	(generator "pcbnew")
	(generator_version "9.0")
	(general
		(thickness 1.294)
		(legacy_teardrops no)
	)
	(paper "A3")
	(title_block
		(title "Kintex 410T devboard")
		(date "2024-04-03")
		(rev "1.1.2")
		(comment 9 "footprints 452-457 of 975")
	)
	(layers
		(0 "F.Cu" mixed)
		(4 "In1.Cu" power)
		(6 "In2.Cu" power)
		(8 "In3.Cu" mixed)
		(10 "In4.Cu" power)
		(12 "In5.Cu" mixed)
		(14 "In6.Cu" power)
		(16 "In7.Cu" mixed)
		(18 "In8.Cu" power)
		(2 "B.Cu" mixed)
		(9 "F.Adhes" user "F.Adhesive")
		(11 "B.Adhes" user "B.Adhesive")
		(13 "F.Paste" user)
		(15 "B.Paste" user)
		(5 "F.SilkS" user "F.Silkscreen")
		(7 "B.SilkS" user "B.Silkscreen")
		(1 "F.Mask" user)
		(3 "B.Mask" user)
		(17 "Dwgs.User" user "User.Drawings")
		(19 "Cmts.User" user "User.Comments")
		(21 "Eco1.User" user "User.Eco1")
		(23 "Eco2.User" user "User.Eco2")
		(25 "Edge.Cuts" user)
		(27 "Margin" user)
		(31 "F.CrtYd" user "F.Courtyard")
		(29 "B.CrtYd" user "B.Courtyard")
		(35 "F.Fab" user)
		(33 "B.Fab" user)
	)
	(footprint "antmicro-footprints:C_0402_1005Metric"
		(layer "F.Cu")
		(at 201.695004 99.9115)
		(descr "Capacitor SMD 0402")
		(tags "capacitor SMD 0402")
		(property "Reference" "C282"
			(at 4.304996 7.9885 0)
			(layer "F.SilkS")
			(effects
				(font
					(size 0.7 0.7)
					(thickness 0.15)
				)
				(justify left bottom)
			)
		)
		(property "Value" "C_100n_0402"
			(at 0 1.169 0)
			(layer "F.Fab")
			(effects
				(font
					(size 0.7 0.7)
					(thickness 0.15)
				)
				(justify left bottom)
			)
		)
		(property "Description" "SMD Multilayer Ceramic Capacitor, 0.1 µF, 50 V, 0402 [1005 Metric], ± 10%, X5R, GRM Series"
			(at 0 0 0)
			(layer "F.Fab")
			(hide yes)
			(effects
				(font
					(size 1.27 1.27)
					(thickness 0.15)
				)
			)
		)
		(property "Author" "Antmicro"
			(at 0 0 0)
			(layer "F.Fab")
			(hide yes)
			(effects
				(font
					(size 1 1)
					(thickness 0.15)
				)
			)
		)
		(property "Dielectric" "X5R"
			(at 0 0 0)
			(layer "F.Fab")
			(hide yes)
			(effects
				(font
					(size 1 1)
					(thickness 0.15)
				)
			)
		)
		(property "License" "Apache-2.0"
			(at 0 0 0)
			(layer "F.Fab")
			(hide yes)
			(effects
				(font
					(size 1 1)
					(thickness 0.15)
				)
			)
		)
		(property "MPN" "GRM155R61H104KE14D"
			(at 0 0 0)
			(layer "F.Fab")
			(hide yes)
			(effects
				(font
					(size 1 1)
					(thickness 0.15)
				)
			)
		)
		(property "Manufacturer" "Murata"
			(at 0 0 0)
			(layer "F.Fab")
			(hide yes)
			(effects
				(font
					(size 1 1)
					(thickness 0.15)
				)
			)
		)
		(property "Val" "100n"
			(at 0 0 0)
			(layer "F.Fab")
			(hide yes)
			(effects
				(font
					(size 1 1)
					(thickness 0.15)
				)
			)
		)
		(property "Voltage" "50V"
			(at 0 0 0)
			(layer "F.Fab")
			(hide yes)
			(effects
				(font
					(size 1 1)
					(thickness 0.15)
				)
			)
		)
		(sheetname "HDMI + Ethernet")
		(sheetfile "hdmi-ethernet.kicad_sch")
		(attr smd)
		(fp_rect
			(start -0.925 -0.47)
			(end 0.925 0.47)
			(stroke
				(width 0.05)
				(type default)
			)
			(fill no)
			(layer "F.CrtYd")
		)
		(fp_line
			(start -0.494 -0.25)
			(end 0.504 -0.25)
			(stroke
				(width 0.15)
				(type solid)
			)
			(layer "F.Fab")
		)
		(fp_line
			(start -0.494 0.248)
			(end -0.494 -0.25)
			(stroke
				(width 0.15)
				(type solid)
			)
			(layer "F.Fab")
		)
		(fp_line
			(start 0.504 -0.25)
			(end 0.504 0.248)
			(stroke
				(width 0.15)
				(type solid)
			)
			(layer "F.Fab")
		)
		(fp_line
			(start 0.504 0.248)
			(end -0.494 0.248)
			(stroke
				(width 0.15)
				(type solid)
			)
			(layer "F.Fab")
		)
		(pad "1" smd roundrect
			(at -0.48 0)
			(size 0.59 0.64)
			(layers "F.Cu" "F.Mask" "F.Paste")
			(roundrect_rratio 0.25)
			(net 1 "GND")
			(pintype "passive")
		)
		(pad "2" smd roundrect
			(at 0.48 0)
			(size 0.59 0.64)
			(layers "F.Cu" "F.Mask" "F.Paste")
			(roundrect_rratio 0.25)
			(net 728 "/HDMI + Ethernet/GBE_AVDDL{slash}PLL")
			(pintype "passive")
		)
	)
	(footprint "antmicro-footprints:C_0603_1608Metric"
		(layer "F.Cu")
		(at 259.45 146.35 -90)
		(descr "Capacitor SMD 0603")
		(tags "capacitor 0603")
		(property "Reference" "C218"
			(at 1 -0.35 90)
			(layer "F.SilkS")
			(effects
				(font
					(size 0.7 0.7)
					(thickness 0.15)
				)
				(justify right bottom)
			)
		)
		(property "Value" "C_10u_25V_0603"
			(at 0 1.6 90)
			(layer "F.Fab")
			(effects
				(font
					(size 0.7 0.7)
					(thickness 0.15)
				)
				(justify right bottom)
			)
		)
		(property "Description" "SMD Multilayer Ceramic Capacitor, 10 µF, 25 V, 0603 [1608 Metric], ± 20%, X5R, C"
			(at 0 0 270)
			(layer "F.Fab")
			(hide yes)
			(effects
				(font
					(size 1.27 1.27)
					(thickness 0.15)
				)
			)
		)
		(property "Author" "Antmicro"
			(at 113.1 405.8 0)
			(layer "F.Fab")
			(hide yes)
			(effects
				(font
					(size 1 1)
					(thickness 0.15)
				)
			)
		)
		(property "Dielectric" ""
			(at 113.1 405.8 0)
			(layer "F.Fab")
			(hide yes)
			(effects
				(font
					(size 1 1)
					(thickness 0.15)
				)
			)
		)
		(property "License" "Apache-2.0"
			(at 113.1 405.8 0)
			(layer "F.Fab")
			(hide yes)
			(effects
				(font
					(size 1 1)
					(thickness 0.15)
				)
			)
		)
		(property "MPN" "C1608X5R1E106M080AC"
			(at 113.1 405.8 0)
			(layer "F.Fab")
			(hide yes)
			(effects
				(font
					(size 1 1)
					(thickness 0.15)
				)
			)
		)
		(property "Manufacturer" "TDK"
			(at 113.1 405.8 0)
			(layer "F.Fab")
			(hide yes)
			(effects
				(font
					(size 1 1)
					(thickness 0.15)
				)
			)
		)
		(property "Val" "10u"
			(at 113.1 405.8 0)
			(layer "F.Fab")
			(hide yes)
			(effects
				(font
					(size 1 1)
					(thickness 0.15)
				)
			)
		)
		(property "Voltage" "25V"
			(at 113.1 405.8 0)
			(layer "F.Fab")
			(hide yes)
			(effects
				(font
					(size 1 1)
					(thickness 0.15)
				)
			)
		)
		(sheetname "USB PHY")
		(sheetfile "usb-phy.kicad_sch")
		(attr smd)
		(fp_line
			(start -0.15 0.4)
			(end 0.15 0.4)
			(stroke
				(width 0.15)
				(type solid)
			)
			(layer "F.SilkS")
		)
		(fp_line
			(start -0.15 -0.4)
			(end 0.15 -0.4)
			(stroke
				(width 0.15)
				(type solid)
			)
			(layer "F.SilkS")
		)
		(fp_rect
			(start -1.25 -0.65)
			(end 1.25 0.65)
			(stroke
				(width 0.05)
				(type solid)
			)
			(fill no)
			(layer "F.CrtYd")
		)
		(fp_rect
			(start -0.8 -0.4)
			(end 0.8 0.4)
			(stroke
				(width 0.15)
				(type solid)
			)
			(fill no)
			(layer "F.Fab")
		)
		(pad "1" smd roundrect
			(at -0.7 0 270)
			(size 0.8 1)
			(layers "F.Cu" "F.Mask" "F.Paste")
			(roundrect_rratio 0.2)
			(net 1 "GND")
			(pintype "passive")
		)
		(pad "2" smd roundrect
			(at 0.7 0 270)
			(size 0.8 1)
			(layers "F.Cu" "F.Mask" "F.Paste")
			(roundrect_rratio 0.2)
			(net 704 "/Power supply/USB_DBG_PD.VBUS")
			(pintype "passive")
		)
	)
	(footprint "antmicro-footprints:R_Array_4x0201_Panasonic_EXB18V"
		(layer "F.Cu")
		(at 247.4 122)
		(property "Reference" "R25"
			(at 1 -0.8 0)
			(layer "F.SilkS")
			(effects
				(font
					(size 0.7 0.7)
					(thickness 0.15)
				)
				(justify right bottom)
			)
		)
		(property "Value" "R_4x33R_0201_array"
			(at -1.1 1.8 0)
			(layer "F.Fab")
			(effects
				(font
					(size 0.7 0.7)
					(thickness 0.15)
				)
				(justify left bottom)
			)
		)
		(property "Description" "Fixed Network Resistor, 33 ohm, Isolated, 4 Resistors, 0502 [1406 Metric], Flat, ± 5%"
			(at 0 0 0)
			(layer "F.Fab")
			(hide yes)
			(effects
				(font
					(size 1.27 1.27)
					(thickness 0.15)
				)
			)
		)
		(property "Author" "Antmicro"
			(at 0 0 0)
			(layer "F.Fab")
			(hide yes)
			(effects
				(font
					(size 1 1)
					(thickness 0.15)
				)
			)
		)
		(property "License" "Apache-2.0"
			(at 0 0 0)
			(layer "F.Fab")
			(hide yes)
			(effects
				(font
					(size 1 1)
					(thickness 0.15)
				)
			)
		)
		(property "MPN" "EXB-18V330JX"
			(at 0 0 0)
			(layer "F.Fab")
			(hide yes)
			(effects
				(font
					(size 1 1)
					(thickness 0.15)
				)
			)
		)
		(property "Manufacturer" "Panasonic"
			(at 0 0 0)
			(layer "F.Fab")
			(hide yes)
			(effects
				(font
					(size 1 1)
					(thickness 0.15)
				)
			)
		)
		(property "Val" "R_4x33R_0201"
			(at 0 0 0)
			(layer "F.Fab")
			(hide yes)
			(effects
				(font
					(size 1 1)
					(thickness 0.15)
				)
			)
		)
		(sheetname "Supervisior MCU")
		(sheetfile "supervisor-mcu.kicad_sch")
		(attr smd)
		(fp_line
			(start -0.8 -0.45)
			(end -0.8 0.45)
			(stroke
				(width 0.12)
				(type solid)
			)
			(layer "F.SilkS")
		)
		(fp_line
			(start 0.8 -0.45)
			(end 0.8 0.45)
			(stroke
				(width 0.12)
				(type solid)
			)
			(layer "F.SilkS")
		)
		(fp_rect
			(start -0.898 -0.66)
			(end 0.898 0.65)
			(stroke
				(width 0.05)
				(type solid)
			)
			(fill no)
			(layer "F.CrtYd")
		)
		(pad "1" smd roundrect
			(at -0.6 0.298)
			(size 0.2 0.4)
			(layers "F.Cu" "F.Mask" "F.Paste")
			(roundrect_rratio 0.25)
			(net 265 "/Supervisior MCU/PWR_ON")
			(pinfunction "R1.1")
			(pintype "passive")
		)
		(pad "2" smd roundrect
			(at -0.202 0.298)
			(size 0.2 0.4)
			(layers "F.Cu" "F.Mask" "F.Paste")
			(roundrect_rratio 0.25)
			(net 1080 "/Supervisior MCU/USB_A19")
			(pinfunction "R2.1")
			(pintype "passive")
		)
		(pad "3" smd roundrect
			(at 0.2 0.298)
			(size 0.2 0.4)
			(layers "F.Cu" "F.Mask" "F.Paste")
			(roundrect_rratio 0.25)
			(net 1075 "/Supervisior MCU/USB_A14")
			(pinfunction "R3.1")
			(pintype "passive")
		)
		(pad "4" smd roundrect
			(at 0.598 0.298)
			(size 0.2 0.4)
			(layers "F.Cu" "F.Mask" "F.Paste")
			(roundrect_rratio 0.25)
			(net 1118 "/Supervisior MCU/USB_CLK0")
			(pinfunction "R4.1")
			(pintype "passive")
		)
		(pad "5" smd roundrect
			(at 0.598 -0.3)
			(size 0.2 0.4)
			(layers "F.Cu" "F.Mask" "F.Paste")
			(roundrect_rratio 0.25)
			(net 1365 "/SUP_MCU.CLKO")
			(pinfunction "R4.2")
			(pintype "passive")
		)
		(pad "6" smd roundrect
			(at 0.2 -0.3)
			(size 0.2 0.4)
			(layers "F.Cu" "F.Mask" "F.Paste")
			(roundrect_rratio 0.25)
			(net 1366 "/SUP_MCU.A14")
			(pinfunction "R3.2")
			(pintype "passive")
		)
		(pad "7" smd roundrect
			(at -0.202 -0.3)
			(size 0.2 0.4)
			(layers "F.Cu" "F.Mask" "F.Paste")
			(roundrect_rratio 0.25)
			(net 1367 "/SUP_MCU.A19")
			(pinfunction "R2.2")
			(pintype "passive")
		)
		(pad "8" smd roundrect
			(at -0.6 -0.3)
			(size 0.2 0.4)
			(layers "F.Cu" "F.Mask" "F.Paste")
			(roundrect_rratio 0.25)
			(net 357 "unconnected-(R25-R1.2-Pad8)")
			(pinfunction "R1.2")
			(pintype "passive+no_connect")
		)
	)
	(footprint "antmicro-footprints:C_1206_3216Metric"
		(layer "F.Cu")
		(at 196.08 177.039 -90)
		(descr "Capacitor SMD 1206")
		(tags "capacitor SMD 1206")
		(property "Reference" "C202"
			(at -4.589 -1.37 45)
			(layer "F.SilkS")
			(effects
				(font
					(size 0.7 0.7)
					(thickness 0.15)
				)
				(justify right bottom)
			)
		)
		(property "Value" "C_47u_16V_1206"
			(at 0 2.1 90)
			(layer "F.Fab")
			(effects
				(font
					(size 0.7 0.7)
					(thickness 0.15)
				)
				(justify right bottom)
			)
		)
		(property "Description" "SMD Multilayer Ceramic Capacitor, 47 µF, 16 V, 1206 [3216 Metric], ± 20%, X5R, C"
			(at 0 0 270)
			(layer "F.Fab")
			(hide yes)
			(effects
				(font
					(size 1.27 1.27)
					(thickness 0.15)
				)
			)
		)
		(property "Author" "Antmicro"
			(at 19.041 373.119 0)
			(layer "F.Fab")
			(hide yes)
			(effects
				(font
					(size 1 1)
					(thickness 0.15)
				)
			)
		)
		(property "Dielectric" "X5R"
			(at 19.041 373.119 0)
			(layer "F.Fab")
			(hide yes)
			(effects
				(font
					(size 1 1)
					(thickness 0.15)
				)
			)
		)
		(property "License" "Apache-2.0"
			(at 19.041 373.119 0)
			(layer "F.Fab")
			(hide yes)
			(effects
				(font
					(size 1 1)
					(thickness 0.15)
				)
			)
		)
		(property "MPN" "C3216X5R1C476M160AB"
			(at 19.041 373.119 0)
			(layer "F.Fab")
			(hide yes)
			(effects
				(font
					(size 1 1)
					(thickness 0.15)
				)
			)
		)
		(property "Manufacturer" "TDK"
			(at 19.041 373.119 0)
			(layer "F.Fab")
			(hide yes)
			(effects
				(font
					(size 1 1)
					(thickness 0.15)
				)
			)
		)
		(property "Val" "47u"
			(at 19.041 373.119 0)
			(layer "F.Fab")
			(hide yes)
			(effects
				(font
					(size 1 1)
					(thickness 0.15)
				)
			)
		)
		(property "Voltage" "16V"
			(at 19.041 373.119 0)
			(layer "F.Fab")
			(hide yes)
			(effects
				(font
					(size 1 1)
					(thickness 0.15)
				)
			)
		)
		(sheetname "Power supply")
		(sheetfile "power-supply.kicad_sch")
		(attr smd)
		(fp_line
			(start 0.8 0.901)
			(end -0.8 0.901)
			(stroke
				(width 0.15)
				(type solid)
			)
			(layer "F.SilkS")
		)
		(fp_line
			(start 0.8 -0.899)
			(end -0.8 -0.899)
			(stroke
				(width 0.15)
				(type solid)
			)
			(layer "F.SilkS")
		)
		(fp_rect
			(start -2.325 -1.15)
			(end 2.325 1.15)
			(stroke
				(width 0.05)
				(type default)
			)
			(fill no)
			(layer "F.CrtYd")
		)
		(fp_rect
			(start -1.6 -0.799)
			(end 1.6 0.801)
			(stroke
				(width 0.15)
				(type solid)
			)
			(fill no)
			(layer "F.Fab")
		)
		(pad "1" smd roundrect
			(at -1.5 0.001 270)
			(size 1.15 1.8)
			(layers "F.Cu" "F.Mask" "F.Paste")
			(roundrect_rratio 0.25)
			(net 1 "GND")
			(pintype "passive")
		)
		(pad "2" smd roundrect
			(at 1.5 0.001 270)
			(size 1.15 1.8)
			(layers "F.Cu" "F.Mask" "F.Paste")
			(roundrect_rratio 0.25)
			(net 956 "/DC-DC Converters/POE_DC")
			(pintype "passive")
		)
	)
	(footprint "antmicro-footprints:R_0402_1005Metric"
		(layer "F.Cu")
		(at 236.35 144.45 180)
		(descr "Resistor SMD 0402")
		(tags "resistor SMD 0402")
		(property "Reference" "R184"
			(at 1.05 -4.45 180)
			(layer "F.SilkS")
			(effects
				(font
					(size 0.7 0.7)
					(thickness 0.15)
				)
				(justify left bottom)
			)
		)
		(property "Value" "R_33R_0402"
			(at 0 1.4 180)
			(layer "F.Fab")
			(effects
				(font
					(size 0.7 0.7)
					(thickness 0.15)
				)
				(justify left bottom)
			)
		)
		(property "Description" "SMD Chip Resistor, 33 ohm, ± 1%, 62.5 mW, 0402 [1005 Metric], Thick Film, General Purpose"
			(at 0 0 180)
			(layer "F.Fab")
			(hide yes)
			(effects
				(font
					(size 1.27 1.27)
					(thickness 0.15)
				)
			)
		)
		(property "Author" "Antmicro"
			(at 472.7 288.9 0)
			(layer "F.Fab")
			(hide yes)
			(effects
				(font
					(size 1 1)
					(thickness 0.15)
				)
			)
		)
		(property "License" "Apache-2.0"
			(at 472.7 288.9 0)
			(layer "F.Fab")
			(hide yes)
			(effects
				(font
					(size 1 1)
					(thickness 0.15)
				)
			)
		)
		(property "MPN" "CR0402-FX-33R0GLF"
			(at 472.7 288.9 0)
			(layer "F.Fab")
			(hide yes)
			(effects
				(font
					(size 1 1)
					(thickness 0.15)
				)
			)
		)
		(property "Manufacturer" "Bourns"
			(at 472.7 288.9 0)
			(layer "F.Fab")
			(hide yes)
			(effects
				(font
					(size 1 1)
					(thickness 0.15)
				)
			)
		)
		(property "Tolerance" "1%"
			(at 472.7 288.9 0)
			(layer "F.Fab")
			(hide yes)
			(effects
				(font
					(size 1 1)
					(thickness 0.15)
				)
			)
		)
		(property "Val" "33R"
			(at 472.7 288.9 0)
			(layer "F.Fab")
			(hide yes)
			(effects
				(font
					(size 1 1)
					(thickness 0.15)
				)
			)
		)
		(sheetname "USB PHY")
		(sheetfile "usb-phy.kicad_sch")
		(attr smd)
		(fp_rect
			(start -0.925 -0.47)
			(end 0.925 0.47)
			(stroke
				(width 0.05)
				(type default)
			)
			(fill no)
			(layer "F.CrtYd")
		)
		(fp_rect
			(start -0.5 -0.25)
			(end 0.5 0.25)
			(stroke
				(width 0.15)
				(type solid)
			)
			(fill no)
			(layer "F.Fab")
		)
		(pad "1" smd roundrect
			(at -0.48 0 180)
			(size 0.59 0.64)
			(layers "F.Cu" "F.Mask" "F.Paste")
			(roundrect_rratio 0.25)
			(net 376 "Net-(U23-B3Y)")
			(pintype "passive")
		)
		(pad "2" smd roundrect
			(at 0.48 0 180)
			(size 0.59 0.64)
			(layers "F.Cu" "F.Mask" "F.Paste")
			(roundrect_rratio 0.25)
			(net 1297 "/USB_SPI.~{CS}")
			(pintype "passive")
		)
	)
	(footprint "antmicro-footprints:C_0805_2012Metric"
		(layer "F.Cu")
		(at 159.0125 178.2)
		(descr "Capacitor SMD 0805")
		(tags "capacitor SMD 0805")
		(property "Reference" "C319"
			(at 2.4875 0.8 0)
			(layer "F.SilkS")
			(effects
				(font
					(size 0.7 0.7)
					(thickness 0.15)
				)
				(justify left bottom)
			)
		)
		(property "Value" "C_22u_25V_0805"
			(at 0 1.947 0)
			(layer "F.Fab")
			(effects
				(font
					(size 0.7 0.7)
					(thickness 0.15)
				)
				(justify left bottom)
			)
		)
		(property "Description" "SMT Multilayer Ceramic Capacitor, 22uF, +/-20%, 25V, X5R, 0805 [2012 Metric]"
			(at 0 0 0)
			(layer "F.Fab")
			(hide yes)
			(effects
				(font
					(size 1.27 1.27)
					(thickness 0.15)
				)
			)
		)
		(property "Author" "Antmicro"
			(at 0 0 0)
			(layer "F.Fab")
			(hide yes)
			(effects
				(font
					(size 1 1)
					(thickness 0.15)
				)
			)
		)
		(property "Dielectric" "X5R"
			(at 0 0 0)
			(layer "F.Fab")
			(hide yes)
			(effects
				(font
					(size 1 1)
					(thickness 0.15)
				)
			)
		)
		(property "License" "Apache-2.0"
			(at 0 0 0)
			(layer "F.Fab")
			(hide yes)
			(effects
				(font
					(size 1 1)
					(thickness 0.15)
				)
			)
		)
		(property "MPN" "CL21A226MAYNNNE"
			(at 0 0 0)
			(layer "F.Fab")
			(hide yes)
			(effects
				(font
					(size 1 1)
					(thickness 0.15)
				)
			)
		)
		(property "Manufacturer" "Samsung Electro-Mechanics"
			(at 0 0 0)
			(layer "F.Fab")
			(hide yes)
			(effects
				(font
					(size 1 1)
					(thickness 0.15)
				)
			)
		)
		(property "Val" "22u"
			(at 0 0 0)
			(layer "F.Fab")
			(hide yes)
			(effects
				(font
					(size 1 1)
					(thickness 0.15)
				)
			)
		)
		(property "Voltage" "25V"
			(at 0 0 0)
			(layer "F.Fab")
			(hide yes)
			(effects
				(font
					(size 1 1)
					(thickness 0.15)
				)
			)
		)
		(sheetname "DC-DC Converters")
		(sheetfile "dc-dc.kicad_sch")
		(attr smd)
		(fp_line
			(start -0.3 -0.7)
			(end 0.3 -0.7)
			(stroke
				(width 0.15)
				(type solid)
			)
			(layer "F.SilkS")
		)
		(fp_line
			(start -0.3 0.7)
			(end 0.3 0.7)
			(stroke
				(width 0.15)
				(type solid)
			)
			(layer "F.SilkS")
		)
		(fp_rect
			(start 1.95 -0.9)
			(end -1.95 0.9)
			(stroke
				(width 0.05)
				(type default)
			)
			(fill no)
			(layer "F.CrtYd")
		)
		(fp_rect
			(start -0.95 -0.675)
			(end 0.95 0.675)
			(stroke
				(width 0.15)
				(type solid)
			)
			(fill no)
			(layer "F.Fab")
		)
		(pad "1" smd roundrect
			(at -1.1 0)
			(size 1.2 1.3)
			(layers "F.Cu" "F.Mask" "F.Paste")
			(roundrect_rratio 0.25)
			(net 1 "GND")
			(pintype "passive")
		)
		(pad "2" smd roundrect
			(at 1.1 0)
			(size 1.2 1.3)
			(layers "F.Cu" "F.Mask" "F.Paste")
			(roundrect_rratio 0.25)
			(net 702 "VDC")
			(pintype "passive")
		)
	)
)
